(kicad_pcb
	(version 20241229)
	(generator "pcbnew")
	(generator_version "9.0")
	(general
		(thickness 1.294)
		(legacy_teardrops no)
	)
	(paper "A3")
	(title_block
		(title "Kintex 410T devboard")
		(date "2024-04-03")
		(rev "1.1.2")
		(comment 9 "footprints 691-695 of 975")
	)
	(layers
		(0 "F.Cu" mixed)
		(4 "In1.Cu" power)
		(6 "In2.Cu" power)
		(8 "In3.Cu" mixed)
		(10 "In4.Cu" power)
		(12 "In5.Cu" mixed)
		(14 "In6.Cu" power)
		(16 "In7.Cu" mixed)
		(18 "In8.Cu" power)
		(2 "B.Cu" mixed)
		(9 "F.Adhes" user "F.Adhesive")
		(11 "B.Adhes" user "B.Adhesive")
		(13 "F.Paste" user)
		(15 "B.Paste" user)
		(5 "F.SilkS" user "F.Silkscreen")
		(7 "B.SilkS" user "B.Silkscreen")
		(1 "F.Mask" user)
		(3 "B.Mask" user)
		(17 "Dwgs.User" user "User.Drawings")
		(19 "Cmts.User" user "User.Comments")
		(21 "Eco1.User" user "User.Eco1")
		(23 "Eco2.User" user "User.Eco2")
		(25 "Edge.Cuts" user)
		(27 "Margin" user)
		(31 "F.CrtYd" user "F.Courtyard")
		(29 "B.CrtYd" user "B.Courtyard")
		(35 "F.Fab" user)
		(33 "B.Fab" user)
	)
	(footprint "antmicro-footprints:R_Array_4x0201_Panasonic_EXB18V"
		(layer "B.Cu")
		(at 251.901 127.9)
		(property "Reference" "R22"
			(at 1.099 -0.725 0)
			(layer "B.SilkS")
			(effects
				(font
					(size 0.7 0.7)
					(thickness 0.15)
				)
				(justify left bottom mirror)
			)
		)
		(property "Value" "R_4x33R_0201_array"
			(at -1.1 -1.8 0)
			(layer "B.Fab")
			(effects
				(font
					(size 0.7 0.7)
					(thickness 0.15)
				)
				(justify right bottom mirror)
			)
		)
		(property "Description" "Fixed Network Resistor, 33 ohm, Isolated, 4 Resistors, 0502 [1406 Metric], Flat, ± 5%"
			(at 0 0 0)
			(layer "F.Fab")
			(hide yes)
			(effects
				(font
					(size 1.27 1.27)
					(thickness 0.15)
				)
			)
		)
		(property "Author" "Antmicro"
			(at 0 0 0)
			(layer "B.Fab")
			(hide yes)
			(effects
				(font
					(size 1 1)
					(thickness 0.15)
				)
				(justify mirror)
			)
		)
		(property "License" "Apache-2.0"
			(at 0 0 0)
			(layer "B.Fab")
			(hide yes)
			(effects
				(font
					(size 1 1)
					(thickness 0.15)
				)
				(justify mirror)
			)
		)
		(property "MPN" "EXB-18V330JX"
			(at 0 0 0)
			(layer "B.Fab")
			(hide yes)
			(effects
				(font
					(size 1 1)
					(thickness 0.15)
				)
				(justify mirror)
			)
		)
		(property "Manufacturer" "Panasonic"
			(at 0 0 0)
			(layer "B.Fab")
			(hide yes)
			(effects
				(font
					(size 1 1)
					(thickness 0.15)
				)
				(justify mirror)
			)
		)
		(property "Val" "R_4x33R_0201"
			(at 0 0 0)
			(layer "B.Fab")
			(hide yes)
			(effects
				(font
					(size 1 1)
					(thickness 0.15)
				)
				(justify mirror)
			)
		)
		(sheetname "Supervisior MCU")
		(sheetfile "supervisor-mcu.kicad_sch")
		(attr smd)
		(fp_line
			(start -0.8 0.45)
			(end -0.8 -0.45)
			(stroke
				(width 0.12)
				(type solid)
			)
			(layer "B.SilkS")
		)
		(fp_line
			(start 0.8 0.45)
			(end 0.8 -0.45)
			(stroke
				(width 0.12)
				(type solid)
			)
			(layer "B.SilkS")
		)
		(fp_rect
			(start -0.898 0.66)
			(end 0.898 -0.65)
			(stroke
				(width 0.05)
				(type solid)
			)
			(fill no)
			(layer "B.CrtYd")
		)
		(pad "1" smd roundrect
			(at -0.6 -0.298)
			(size 0.2 0.4)
			(layers "B.Cu" "B.Mask" "B.Paste")
			(roundrect_rratio 0.25)
			(net 1340 "/SUP_MCU.SW_STATE")
			(pinfunction "R1.1")
			(pintype "passive")
		)
		(pad "2" smd roundrect
			(at -0.202 -0.298)
			(size 0.2 0.4)
			(layers "B.Cu" "B.Mask" "B.Paste")
			(roundrect_rratio 0.25)
			(net 1332 "/SUP_MCU.CCLK")
			(pinfunction "R2.1")
			(pintype "passive")
		)
		(pad "3" smd roundrect
			(at 0.2 -0.298)
			(size 0.2 0.4)
			(layers "B.Cu" "B.Mask" "B.Paste")
			(roundrect_rratio 0.25)
			(net 348 "unconnected-(R22-R3.1-Pad3)")
			(pinfunction "R3.1")
			(pintype "passive+no_connect")
		)
		(pad "4" smd roundrect
			(at 0.598 -0.298)
			(size 0.2 0.4)
			(layers "B.Cu" "B.Mask" "B.Paste")
			(roundrect_rratio 0.25)
			(net 1358 "/SUP_MCU.A2")
			(pinfunction "R4.1")
			(pintype "passive")
		)
		(pad "5" smd roundrect
			(at 0.598 0.3)
			(size 0.2 0.4)
			(layers "B.Cu" "B.Mask" "B.Paste")
			(roundrect_rratio 0.25)
			(net 1063 "/Supervisior MCU/USB_A2")
			(pinfunction "R4.2")
			(pintype "passive")
		)
		(pad "6" smd roundrect
			(at 0.2 0.3)
			(size 0.2 0.4)
			(layers "B.Cu" "B.Mask" "B.Paste")
			(roundrect_rratio 0.25)
			(net 1108 "/Supervisior MCU/PWR_RST")
			(pinfunction "R3.2")
			(pintype "passive")
		)
		(pad "7" smd roundrect
			(at -0.202 0.3)
			(size 0.2 0.4)
			(layers "B.Cu" "B.Mask" "B.Paste")
			(roundrect_rratio 0.25)
			(net 112 "/Supervisior MCU/SAM_FPGA_CCLK")
			(pinfunction "R2.2")
			(pintype "passive")
		)
		(pad "8" smd roundrect
			(at -0.6 0.3)
			(size 0.2 0.4)
			(layers "B.Cu" "B.Mask" "B.Paste")
			(roundrect_rratio 0.25)
			(net 276 "/Supervisior MCU/SW_STATE")
			(pinfunction "R1.2")
			(pintype "passive")
		)
	)
	(footprint "antmicro-footprints:USON-10_2.5x1mm_P0.5mm"
		(layer "B.Cu")
		(at 190.000001 74.000001 90)
		(descr "USON-10 2.5x1mm_ Pitch 0.5mm")
		(tags "USON-10 2.5x1mm Pitch 0.5mm")
		(property "Reference" "U2"
			(at -1.649999 0.799999 0)
			(layer "B.SilkS")
			(effects
				(font
					(size 0.7 0.7)
					(thickness 0.15)
				)
				(justify left bottom mirror)
			)
		)
		(property "Value" "TPD4E05U06QDQARQ1"
			(at 0.018 -2.499 270)
			(layer "B.Fab")
			(effects
				(font
					(size 0.7 0.7)
					(thickness 0.15)
				)
				(justify left bottom mirror)
			)
		)
		(property "Description" "ESD protection"
			(at 0 0 90)
			(layer "F.Fab")
			(hide yes)
			(effects
				(font
					(size 1.27 1.27)
					(thickness 0.15)
				)
			)
		)
		(property "Author" "Antmicro"
			(at 264.000002 -116 0)
			(layer "B.Fab")
			(hide yes)
			(effects
				(font
					(size 1 1)
					(thickness 0.15)
				)
				(justify mirror)
			)
		)
		(property "License" "Apache-2.0"
			(at 264.000002 -116 0)
			(layer "B.Fab")
			(hide yes)
			(effects
				(font
					(size 1 1)
					(thickness 0.15)
				)
				(justify mirror)
			)
		)
		(property "MPN" "TPD4E05U06QDQARQ1"
			(at 264.000002 -116 0)
			(layer "B.Fab")
			(hide yes)
			(effects
				(font
					(size 1 1)
					(thickness 0.15)
				)
				(justify mirror)
			)
		)
		(property "Manufacturer" "Texas Instruments"
			(at 264.000002 -116 0)
			(layer "B.Fab")
			(hide yes)
			(effects
				(font
					(size 1 1)
					(thickness 0.15)
				)
				(justify mirror)
			)
		)
		(sheetname "FPGA Config")
		(sheetfile "fpga-config.kicad_sch")
		(attr smd)
		(fp_line
			(start 0.498 -1.398)
			(end -0.5 -1.398)
			(stroke
				(width 0.15)
				(type solid)
			)
			(layer "B.SilkS")
		)
		(fp_line
			(start 0.498 1.401)
			(end -0.5 1.401)
			(stroke
				(width 0.15)
				(type solid)
			)
			(layer "B.SilkS")
		)
		(fp_circle
			(center -0.68 1.27)
			(end -0.63 1.27)
			(stroke
				(width 0.15)
				(type solid)
			)
			(fill yes)
			(layer "B.SilkS")
		)
		(fp_rect
			(start -0.8 1.5)
			(end 0.8 -1.499)
			(stroke
				(width 0.05)
				(type solid)
			)
			(fill no)
			(layer "B.CrtYd")
		)
		(fp_line
			(start -0.5 -1.249)
			(end 0.498 -1.249)
			(stroke
				(width 0.15)
				(type solid)
			)
			(layer "B.Fab")
		)
		(fp_line
			(start -0.5 1)
			(end -0.5 -1.249)
			(stroke
				(width 0.15)
				(type solid)
			)
			(layer "B.Fab")
		)
		(fp_line
			(start 0.498 1.25)
			(end 0.498 -1.249)
			(stroke
				(width 0.15)
				(type solid)
			)
			(layer "B.Fab")
		)
		(fp_line
			(start 0.498 1.25)
			(end -0.25 1.25)
			(stroke
				(width 0.15)
				(type solid)
			)
			(layer "B.Fab")
		)
		(fp_line
			(start -0.25 1.25)
			(end -0.5 1)
			(stroke
				(width 0.15)
				(type solid)
			)
			(layer "B.Fab")
		)
		(pad "1" smd roundrect
			(at -0.387 1 180)
			(size 0.25 0.55)
			(layers "B.Cu" "B.Mask" "B.Paste")
			(roundrect_rratio 0.25)
			(net 161 "/FPGA Config/JTAG.TMS")
			(pintype "passive")
		)
		(pad "2" smd roundrect
			(at -0.387 0.5 180)
			(size 0.25 0.55)
			(layers "B.Cu" "B.Mask" "B.Paste")
			(roundrect_rratio 0.25)
			(net 165 "/FPGA Config/JTAG.TCK")
			(pintype "passive")
		)
		(pad "3" smd roundrect
			(at -0.387 0 180)
			(size 0.4 0.55)
			(layers "B.Cu" "B.Mask" "B.Paste")
			(roundrect_rratio 0.25)
			(net 1 "GND")
			(pintype "power_in")
		)
		(pad "4" smd roundrect
			(at -0.387 -0.498 180)
			(size 0.25 0.55)
			(layers "B.Cu" "B.Mask" "B.Paste")
			(roundrect_rratio 0.25)
			(net 190 "/FPGA Config/JTAG.TDO")
			(pintype "passive")
		)
		(pad "5" smd roundrect
			(at -0.387 -0.998 180)
			(size 0.25 0.55)
			(layers "B.Cu" "B.Mask" "B.Paste")
			(roundrect_rratio 0.25)
			(net 220 "/FPGA Config/JTAG.TDI")
			(pintype "passive")
		)
		(pad "6" smd roundrect
			(at 0.385 -0.998 180)
			(size 0.25 0.55)
			(layers "B.Cu" "B.Mask" "B.Paste")
			(roundrect_rratio 0.25)
			(net 220 "/FPGA Config/JTAG.TDI")
			(pintype "passive")
		)
		(pad "7" smd roundrect
			(at 0.385 -0.498 180)
			(size 0.25 0.55)
			(layers "B.Cu" "B.Mask" "B.Paste")
			(roundrect_rratio 0.25)
			(net 190 "/FPGA Config/JTAG.TDO")
			(pintype "passive")
		)
		(pad "8" smd roundrect
			(at 0.385 0 180)
			(size 0.4 0.55)
			(layers "B.Cu" "B.Mask" "B.Paste")
			(roundrect_rratio 0.25)
			(net 1 "GND")
			(pintype "passive")
		)
		(pad "9" smd roundrect
			(at 0.385 0.5 180)
			(size 0.25 0.55)
			(layers "B.Cu" "B.Mask" "B.Paste")
			(roundrect_rratio 0.25)
			(net 165 "/FPGA Config/JTAG.TCK")
			(pintype "passive")
		)
		(pad "10" smd roundrect
			(at 0.385 1 180)
			(size 0.25 0.55)
			(layers "B.Cu" "B.Mask" "B.Paste")
			(roundrect_rratio 0.25)
			(net 161 "/FPGA Config/JTAG.TMS")
			(pintype "passive")
		)
	)
	(footprint "antmicro-footprints:NetTie-2_SMD_Pad0.127mm"
		(layer "B.Cu")
		(at 196.76 86.9 -135)
		(descr "Net tie, 2 pin, 0.127mm  SMD pads")
		(tags "net tie")
		(property "Reference" "NT37"
			(at -0.128 1.345 45)
			(layer "B.SilkS")
			(hide yes)
			(effects
				(font
					(size 0.7 0.7)
					(thickness 0.15)
				)
				(justify left bottom mirror)
			)
		)
		(property "Value" "Net-Tie_2"
			(at 0 -1.199 45)
			(layer "B.Fab")
			(effects
				(font
					(size 0.7 0.7)
					(thickness 0.15)
				)
				(justify left bottom mirror)
			)
		)
		(property "Description" "Net tie, 2 pins"
			(at 0 0 225)
			(layer "F.Fab")
			(hide yes)
			(effects
				(font
					(size 1.27 1.27)
					(thickness 0.15)
				)
			)
		)
		(property "Author" "Antmicro"
			(at 274.442751 287.47791 0)
			(layer "B.Fab")
			(hide yes)
			(effects
				(font
					(size 1 1)
					(thickness 0.15)
				)
				(justify mirror)
			)
		)
		(property "License" "Apache-2.0"
			(at 274.442751 287.47791 0)
			(layer "B.Fab")
			(hide yes)
			(effects
				(font
					(size 1 1)
					(thickness 0.15)
				)
				(justify mirror)
			)
		)
		(property "MPN" ""
			(at 274.442751 287.47791 0)
			(layer "B.Fab")
			(hide yes)
			(effects
				(font
					(size 1 1)
					(thickness 0.15)
				)
				(justify mirror)
			)
		)
		(property "Manufacturer" ""
			(at 274.442751 287.47791 0)
			(layer "B.Fab")
			(hide yes)
			(effects
				(font
					(size 1 1)
					(thickness 0.15)
				)
				(justify mirror)
			)
		)
		(sheetname "DC-DC Converters")
		(sheetfile "dc-dc.kicad_sch")
		(attr exclude_from_pos_files)
		(net_tie_pad_groups "1, 2")
		(fp_poly
			(pts
				(xy -0.0635 0.0635) (xy 0.0625 0.0635) (xy 0.0625 -0.0635) (xy -0.0635 -0.0635)
			)
			(stroke
				(width 0)
				(type solid)
			)
			(fill yes)
			(layer "B.Cu")
		)
		(pad "1" smd roundrect
			(at -0.127001 0 45)
			(size 0.127 0.127)
			(layers "B.Cu")
			(roundrect_rratio 0.5)
			(chamfer_ratio 0)
			(chamfer top_left bottom_left)
			(net 1 "GND")
			(pinfunction "1")
			(pintype "passive")
		)
		(pad "2" smd roundrect
			(at 0.125999 0 225)
			(size 0.127 0.127)
			(layers "B.Cu")
			(roundrect_rratio 0.5)
			(chamfer_ratio 0)
			(chamfer top_left bottom_left)
			(net 1225 "/DC-DC Converters/SENSE_1V2_N")
			(pinfunction "2")
			(pintype "passive")
		)
	)
	(footprint "antmicro-footprints:C_0201"
		(layer "B.Cu")
		(at 192.3 116.2 -45)
		(descr "Capacitor SMD 0201")
		(tags "capacitor SMD 0201")
		(property "Reference" "C124"
			(at 1.467247 -0.371231 315)
			(unlocked yes)
			(layer "B.SilkS")
			(effects
				(font
					(size 0.7 0.7)
					(thickness 0.15)
				)
				(justify left bottom mirror)
			)
		)
		(property "Value" "C_100n_0201"
			(at 0 -1.399999 135)
			(layer "B.Fab")
			(effects
				(font
					(size 0.7 0.7)
					(thickness 0.15)
				)
				(justify left bottom mirror)
			)
		)
		(property "Description" "SMD Multilayer Ceramic Capacitor, 0.1 µF, 6.3 V, 0201 [0603 Metric], ± 10%, X6S, CC Series"
			(at 0 0 315)
			(layer "F.Fab")
			(hide yes)
			(effects
				(font
					(size 1.27 1.27)
					(thickness 0.15)
				)
			)
		)
		(property "Author" "Antmicro"
			(at -25.842442 170.010826 0)
			(layer "B.Fab")
			(hide yes)
			(effects
				(font
					(size 1 1)
					(thickness 0.15)
				)
				(justify mirror)
			)
		)
		(property "Dielectric" ""
			(at -25.842442 170.010826 0)
			(layer "B.Fab")
			(hide yes)
			(effects
				(font
					(size 1 1)
					(thickness 0.15)
				)
				(justify mirror)
			)
		)
		(property "License" "Apache-2.0"
			(at -25.842442 170.010826 0)
			(layer "B.Fab")
			(hide yes)
			(effects
				(font
					(size 1 1)
					(thickness 0.15)
				)
				(justify mirror)
			)
		)
		(property "MPN" "CC0201KRX6S5BB104"
			(at -25.842442 170.010826 0)
			(layer "B.Fab")
			(hide yes)
			(effects
				(font
					(size 1 1)
					(thickness 0.15)
				)
				(justify mirror)
			)
		)
		(property "Manufacturer" "YAGEO"
			(at -25.842442 170.010826 0)
			(layer "B.Fab")
			(hide yes)
			(effects
				(font
					(size 1 1)
					(thickness 0.15)
				)
				(justify mirror)
			)
		)
		(property "Val" "100n"
			(at -25.842442 170.010826 0)
			(layer "B.Fab")
			(hide yes)
			(effects
				(font
					(size 1 1)
					(thickness 0.15)
				)
				(justify mirror)
			)
		)
		(property "Voltage" ""
			(at -25.842442 170.010826 0)
			(layer "B.Fab")
			(hide yes)
			(effects
				(font
					(size 1 1)
					(thickness 0.15)
				)
				(justify mirror)
			)
		)
		(sheetname "FPGA supply")
		(sheetfile "fpga-supply.kicad_sch")
		(attr smd)
		(fp_poly
			(pts
				(xy -0.7 0.35) (xy 0.7 0.35) (xy 0.7 -0.35) (xy -0.7 -0.35)
			)
			(stroke
				(width 0.05)
				(type default)
			)
			(fill no)
			(layer "B.CrtYd")
		)
		(fp_poly
			(pts
				(xy 0.3 -0.15) (xy -0.301 -0.15) (xy -0.301 0.149) (xy 0.3 0.149)
			)
			(stroke
				(width 0.15)
				(type solid)
			)
			(fill no)
			(layer "B.Fab")
		)
		(pad "" smd roundrect
			(at -0.349 0.002 315)
			(size 0.318 0.36)
			(layers "B.Paste")
			(roundrect_rratio 0.25)
		)
		(pad "" smd roundrect
			(at 0.341 0.002 315)
			(size 0.318 0.36)
			(layers "B.Paste")
			(roundrect_rratio 0.25)
		)
		(pad "1" smd roundrect
			(at -0.321 0.002 315)
			(size 0.46 0.4)
			(layers "B.Cu" "B.Mask")
			(roundrect_rratio 0.25)
			(net 6 "+1V0_MGTAVCC")
			(pintype "passive")
		)
		(pad "2" smd roundrect
			(at 0.32 0.002 315)
			(size 0.46 0.4)
			(layers "B.Cu" "B.Mask")
			(roundrect_rratio 0.25)
			(net 1 "GND")
			(pintype "passive")
		)
	)
	(footprint "antmicro-footprints:C_0402_1005Metric"
		(layer "B.Cu")
		(at 215.875 118.025 180)
		(descr "Capacitor SMD 0402")
		(tags "capacitor SMD 0402")
		(property "Reference" "C15"
			(at -1.1 -1.225 0)
			(layer "B.SilkS")
			(effects
				(font
					(size 0.7 0.7)
					(thickness 0.15)
				)
				(justify left bottom mirror)
			)
		)
		(property "Value" "C_100n_0402"
			(at 0 -1.169 0)
			(layer "B.Fab")
			(effects
				(font
					(size 0.7 0.7)
					(thickness 0.15)
				)
				(justify left bottom mirror)
			)
		)
		(property "Description" "SMD Multilayer Ceramic Capacitor, 0.1 µF, 50 V, 0402 [1005 Metric], ± 10%, X5R, GRM Series"
			(at 0 0 180)
			(layer "F.Fab")
			(hide yes)
			(effects
				(font
					(size 1.27 1.27)
					(thickness 0.15)
				)
			)
		)
		(property "Author" "Antmicro"
			(at 431.75 236.05 0)
			(layer "B.Fab")
			(hide yes)
			(effects
				(font
					(size 1 1)
					(thickness 0.15)
				)
				(justify mirror)
			)
		)
		(property "Dielectric" "X5R"
			(at 431.75 236.05 0)
			(layer "B.Fab")
			(hide yes)
			(effects
				(font
					(size 1 1)
					(thickness 0.15)
				)
				(justify mirror)
			)
		)
		(property "License" "Apache-2.0"
			(at 431.75 236.05 0)
			(layer "B.Fab")
			(hide yes)
			(effects
				(font
					(size 1 1)
					(thickness 0.15)
				)
				(justify mirror)
			)
		)
		(property "MPN" "GRM155R61H104KE14D"
			(at 431.75 236.05 0)
			(layer "B.Fab")
			(hide yes)
			(effects
				(font
					(size 1 1)
					(thickness 0.15)
				)
				(justify mirror)
			)
		)
		(property "Manufacturer" "Murata"
			(at 431.75 236.05 0)
			(layer "B.Fab")
			(hide yes)
			(effects
				(font
					(size 1 1)
					(thickness 0.15)
				)
				(justify mirror)
			)
		)
		(property "Val" "100n"
			(at 431.75 236.05 0)
			(layer "B.Fab")
			(hide yes)
			(effects
				(font
					(size 1 1)
					(thickness 0.15)
				)
				(justify mirror)
			)
		)
		(property "Voltage" "50V"
			(at 431.75 236.05 0)
			(layer "B.Fab")
			(hide yes)
			(effects
				(font
					(size 1 1)
					(thickness 0.15)
				)
				(justify mirror)
			)
		)
		(sheetname "FPGA Bank 16 & 17")
		(sheetfile "fpga-bank-16-17.kicad_sch")
		(attr smd)
		(fp_rect
			(start -0.925 0.47)
			(end 0.925 -0.47)
			(stroke
				(width 0.05)
				(type default)
			)
			(fill no)
			(layer "B.CrtYd")
		)
		(fp_line
			(start 0.504 0.25)
			(end 0.504 -0.248)
			(stroke
				(width 0.15)
				(type solid)
			)
			(layer "B.Fab")
		)
		(fp_line
			(start 0.504 -0.248)
			(end -0.494 -0.248)
			(stroke
				(width 0.15)
				(type solid)
			)
			(layer "B.Fab")
		)
		(fp_line
			(start -0.494 0.25)
			(end 0.504 0.25)
			(stroke
				(width 0.15)
				(type solid)
			)
			(layer "B.Fab")
		)
		(fp_line
			(start -0.494 -0.248)
			(end -0.494 0.25)
			(stroke
				(width 0.15)
				(type solid)
			)
			(layer "B.Fab")
		)
		(pad "1" smd roundrect
			(at -0.48 0 180)
			(size 0.59 0.64)
			(layers "B.Cu" "B.Mask" "B.Paste")
			(roundrect_rratio 0.25)
			(net 1 "GND")
			(pintype "passive")
		)
		(pad "2" smd roundrect
			(at 0.48 0 180)
			(size 0.59 0.64)
			(layers "B.Cu" "B.Mask" "B.Paste")
			(roundrect_rratio 0.25)
			(net 3 "VCC_USR_B")
			(pintype "passive")
		)
	)
)
